# BASEBOARD_FAB2 (Tioga Pass) — schematic netlist excerpt (pin names and nets, part order shuffled) for the footprints in the layout excerpt that follows; sources: Cadence DE-HDL packaged netlist, KiCad conversion of Wiwynn_Tioga_Pass_MB.brd

C4E7  CAPP  470UF 2.5V 20% ALUM  pkg 3018  page 214 : A = PVCCIO_CPU1 ; B = GND
C1G14  CAP_A  0.1UF 16V 10% X7R  pkg 0402V  page 224 : A = VR_FET_SW_P12V_STBY_PVDDQ_GHJ ; B = GND
C5A2  CAP_A  47UF 4V 20% X5R  pkg 0603V  page 220 : A = PVDDQ_DEF ; B = GND

(kicad_pcb
	(version 20260206)
	(generator "pcbnew")
	(generator_version "10.0")
	(general
		(thickness 1.6)
		(legacy_teardrops no)
	)
	(paper "A4")
	(title_block
		(title "Wiwynn_Tioga_Pass_MB.brd")
		(comment 1 "Tioga Pass / footprints 2282-2284 of 4770")
	)
	(layers
		(0 "F.Cu" signal "TOP")
		(4 "In1.Cu" signal "L2GND")
		(6 "In2.Cu" signal "L3")
		(8 "In3.Cu" signal "L4GND")
		(10 "In4.Cu" signal "L5")
		(12 "In5.Cu" signal "L6GND")
		(14 "In6.Cu" signal "L7VCC")
		(16 "In7.Cu" signal "L8VCC")
		(18 "In8.Cu" signal "L9GND")
		(20 "In9.Cu" signal "L10")
		(22 "In10.Cu" signal "L11GND")
		(24 "In11.Cu" signal "L12")
		(26 "In12.Cu" signal "L13GND")
		(2 "B.Cu" signal "BOTTOM")
		(9 "F.Adhes" user "F.Adhesive")
		(11 "B.Adhes" user "B.Adhesive")
		(13 "F.Paste" user "Package Geometry/Pastemask Top")
		(15 "B.Paste" user "Package Geometry/Pastemask Bottom")
		(5 "F.SilkS" user "Ref Des/Silkscreen Top")
		(7 "B.SilkS" user "Ref Des/Silkscreen Bottom")
		(1 "F.Mask" user "Board Geometry/Soldermask Top")
		(3 "B.Mask" user "Board Geometry/Soldermask Bottom")
		(17 "Dwgs.User" user "User.Drawings")
		(19 "Cmts.User" user "User.Comments")
		(21 "Eco1.User" user "User.Eco1")
		(23 "Eco2.User" user "User.Eco2")
		(25 "Edge.Cuts" user "Board Geometry/Outline")
		(27 "Margin" user)
		(31 "F.CrtYd" user "Package Geometry/Place Bound Top")
		(29 "B.CrtYd" user "Package Geometry/Place Bound Bottom")
		(35 "F.Fab" user "Ref Des/Assembly Top")
		(33 "B.Fab" user "Ref Des/Assembly Bottom")
	)
	(footprint ""
		(layer "F.Cu")
		(at 4.295394 -12.815824 90)
		(property "Reference" "C1G14"
			(at 0 0 90)
			(layer "F.SilkS")
			(hide yes)
			(effects
				(font
					(size 1.27 1.27)
				)
			)
		)
		(property "Value" ""
			(at 0 0 90)
			(layer "F.Fab")
			(effects
				(font
					(size 1.27 1.27)
				)
			)
		)
		(duplicate_pad_numbers_are_jumpers no)
		(fp_rect
			(start 0.3048 -0.1016)
			(end -0.3048 0.9906)
			(stroke
				(width 0)
				(type default)
			)
			(fill no)
			(layer "F.CrtYd")
		)
		(fp_line
			(start 0.3048 -0.1016)
			(end -0.3048 -0.1016)
			(stroke
				(width 0.1)
				(type default)
			)
			(layer "F.Fab")
		)
		(fp_line
			(start -0.3048 -0.1016)
			(end -0.3048 0.9906)
			(stroke
				(width 0.1)
				(type default)
			)
			(layer "F.Fab")
		)
		(fp_line
			(start 0.3048 0.9906)
			(end 0.3048 -0.1016)
			(stroke
				(width 0.1)
				(type default)
			)
			(layer "F.Fab")
		)
		(fp_line
			(start -0.3048 0.9906)
			(end 0.3048 0.9906)
			(stroke
				(width 0.1)
				(type default)
			)
			(layer "F.Fab")
		)
		(pad "1" smd rect
			(at 0 0 90)
			(size 0.508 0.508)
			(layers "F.Cu" "F.Mask" "F.Paste")
			(net "VR_FET_SW_P12V_STBY_PVDDQ_GHJ")
		)
		(pad "2" smd rect
			(at 0 0.889 90)
			(size 0.508 0.508)
			(layers "F.Cu" "F.Mask" "F.Paste")
			(net "GND")
		)
		(zone
			(layer "F.Cu")
			(hatch none 0.5)
			(connect_pads
				(clearance 0)
			)
			(min_thickness 0.25)
			(keepout
				(tracks not_allowed)
				(vias allowed)
				(pads allowed)
				(copperpour not_allowed)
				(footprints allowed)
			)
			(placement
				(enabled no)
				(sheetname "")
			)
			(fill
				(thermal_gap 0.5)
				(thermal_bridge_width 0.5)
				(island_removal_mode 0)
			)
			(polygon
				(pts
					(xy 4.549394 -13.069824) (xy 4.549394 -12.561824) (xy 4.930394 -12.561824) (xy 4.930394 -13.069824)
				)
			)
		)
		(zone
			(layer "F.Cu")
			(hatch none 0.5)
			(connect_pads
				(clearance 0)
			)
			(min_thickness 0.25)
			(keepout
				(tracks allowed)
				(vias not_allowed)
				(pads allowed)
				(copperpour not_allowed)
				(footprints allowed)
			)
			(placement
				(enabled no)
				(sheetname "")
			)
			(fill
				(thermal_gap 0.5)
				(thermal_bridge_width 0.5)
				(island_removal_mode 0)
			)
			(polygon
				(pts
					(xy 4.549394 -13.069824) (xy 4.549394 -12.561824) (xy 4.930394 -12.561824) (xy 4.930394 -13.069824)
				)
			)
		)
	)
	(footprint ""
		(layer "F.Cu")
		(at 164.973 -60.9346 90)
		(property "Reference" "C4E7"
			(at 0.2794 -2.76733 90)
			(unlocked yes)
			(layer "F.SilkS")
			(effects
				(font
					(size 0.7874 0.5842)
					(thickness 0.1524)
				)
			)
		)
		(property "Value" ""
			(at 0 0 90)
			(layer "F.Fab")
			(effects
				(font
					(size 1.27 1.27)
				)
			)
		)
		(duplicate_pad_numbers_are_jumpers no)
		(fp_line
			(start 2.504948 -1.616456)
			(end 2.504948 1.633728)
			(stroke
				(width 0.1524)
				(type default)
			)
			(layer "F.SilkS")
		)
		(fp_line
			(start 1.6002 -1.616456)
			(end 2.504948 -1.616456)
			(stroke
				(width 0.1524)
				(type default)
			)
			(layer "F.SilkS")
		)
		(fp_line
			(start -1.6002 -1.616456)
			(end -2.563114 -1.616456)
			(stroke
				(width 0.1524)
				(type default)
			)
			(layer "F.SilkS")
		)
		(fp_line
			(start -2.563114 -1.616456)
			(end -2.563114 1.633728)
			(stroke
				(width 0.1524)
				(type default)
			)
			(layer "F.SilkS")
		)
		(fp_line
			(start 2.504948 1.633728)
			(end 1.6002 1.633728)
			(stroke
				(width 0.1524)
				(type default)
			)
			(layer "F.SilkS")
		)
		(fp_line
			(start -2.563114 1.633728)
			(end -1.6002 1.633728)
			(stroke
				(width 0.1524)
				(type default)
			)
			(layer "F.SilkS")
		)
		(fp_line
			(start 2.286 7.366)
			(end 2.286 1.63195)
			(stroke
				(width 0.1524)
				(type default)
			)
			(layer "F.SilkS")
		)
		(fp_line
			(start 2.286 7.366)
			(end 1.600708 7.366)
			(stroke
				(width 0.1524)
				(type default)
			)
			(layer "F.SilkS")
		)
		(fp_line
			(start -2.286 7.366)
			(end -2.286 1.632712)
			(stroke
				(width 0.1524)
				(type default)
			)
			(layer "F.SilkS")
		)
		(fp_line
			(start -2.286 7.366)
			(end -1.60147 7.366)
			(stroke
				(width 0.1524)
				(type default)
			)
			(layer "F.SilkS")
		)
		(fp_rect
			(start -2.286 7.366)
			(end 2.286 -0.254)
			(stroke
				(width 0)
				(type default)
			)
			(fill no)
			(layer "F.CrtYd")
		)
		(fp_line
			(start 2.286 -0.254)
			(end 2.286 7.366)
			(stroke
				(width 0.1)
				(type default)
			)
			(layer "F.Fab")
		)
		(fp_line
			(start -2.286 -0.254)
			(end 2.286 -0.254)
			(stroke
				(width 0.1)
				(type default)
			)
			(layer "F.Fab")
		)
		(fp_line
			(start 2.286 7.366)
			(end -2.286 7.366)
			(stroke
				(width 0.1)
				(type default)
			)
			(layer "F.Fab")
		)
		(fp_line
			(start -2.286 7.366)
			(end -2.286 -0.254)
			(stroke
				(width 0.1)
				(type default)
			)
			(layer "F.Fab")
		)
		(pad "1" smd rect
			(at 0 0 90)
			(size 2.54 3.048)
			(layers "F.Cu" "F.Mask" "F.Paste")
			(net "PVCCIO_CPU1")
		)
		(pad "2" smd rect
			(at 0 7.112 90)
			(size 2.54 3.048)
			(layers "F.Cu" "F.Mask" "F.Paste")
			(net "GND")
		)
	)
	(footprint ""
		(layer "F.Cu")
		(at 248.8565 -149.8092 -90)
		(property "Reference" "C5A2"
			(at 1.848866 0.752348 270)
			(unlocked yes)
			(layer "F.SilkS")
			(effects
				(font
					(size 1.27 0.9652)
					(thickness 0.1524)
				)
			)
		)
		(property "Value" ""
			(at 0 0 270)
			(layer "F.Fab")
			(effects
				(font
					(size 1.27 1.27)
				)
			)
		)
		(duplicate_pad_numbers_are_jumpers no)
		(fp_rect
			(start -0.500126 1.598422)
			(end 0.500126 -0.201422)
			(stroke
				(width 0)
				(type default)
			)
			(fill no)
			(layer "F.CrtYd")
		)
		(fp_line
			(start -0.500126 1.598422)
			(end -0.500126 -0.201422)
			(stroke
				(width 0.1)
				(type default)
			)
			(layer "F.Fab")
		)
		(fp_line
			(start 0.500126 1.598422)
			(end -0.500126 1.598422)
			(stroke
				(width 0.1)
				(type default)
			)
			(layer "F.Fab")
		)
		(fp_line
			(start -0.500126 -0.201422)
			(end 0.500126 -0.201422)
			(stroke
				(width 0.1)
				(type default)
			)
			(layer "F.Fab")
		)
		(fp_line
			(start 0.500126 -0.201422)
			(end 0.500126 1.598422)
			(stroke
				(width 0.1)
				(type default)
			)
			(layer "F.Fab")
		)
		(pad "1" smd rect
			(at 0 0 180)
			(size 0.889 0.9906)
			(layers "F.Cu" "F.Mask" "F.Paste")
			(net "PVDDQ_DEF")
		)
		(pad "2" smd rect
			(at 0 1.397 180)
			(size 0.889 0.9906)
			(layers "F.Cu" "F.Mask" "F.Paste")
			(net "GND")
		)
		(zone
			(layer "F.Cu")
			(hatch none 0.5)
			(connect_pads
				(clearance 0)
			)
			(min_thickness 0.25)
			(keepout
				(tracks allowed)
				(vias not_allowed)
				(pads allowed)
				(copperpour not_allowed)
				(footprints allowed)
			)
			(placement
				(enabled no)
				(sheetname "")
			)
			(fill
				(thermal_gap 0.5)
				(thermal_bridge_width 0.5)
				(island_removal_mode 0)
			)
			(polygon
				(pts
					(xy 247.904 -150.3045) (xy 247.904 -149.3139) (xy 248.412 -149.3139) (xy 248.412 -150.3045)
				)
			)
		)
		(zone
			(layer "F.Cu")
			(hatch none 0.5)
			(connect_pads
				(clearance 0)
			)
			(min_thickness 0.25)
			(keepout
				(tracks not_allowed)
				(vias allowed)
				(pads allowed)
				(copperpour not_allowed)
				(footprints allowed)
			)
			(placement
				(enabled no)
				(sheetname "")
			)
			(fill
				(thermal_gap 0.5)
				(thermal_bridge_width 0.5)
				(island_removal_mode 0)
			)
			(polygon
				(pts
					(xy 247.904 -150.3045) (xy 247.904 -149.3139) (xy 248.412 -149.3139) (xy 248.412 -150.3045)
				)
			)
		)
	)
)
